(kicad_pcb
	(version 20221018)
	(generator pcbnew)
	(general
    (thickness 1.656)
  )
	(paper "A4")
	(title_block
    (title "SDI-MIPI Bridge")
    (date "2023-08-09")
    (rev "1.3.4")
    (company "Antmicro")
		(comment 9 "footprints 8-12 of 190")
	)
	(layers
    (0 "F.Cu" signal)
    (1 "In1.Cu" power)
    (2 "In2.Cu" power)
    (3 "In3.Cu" signal)
    (4 "In4.Cu" signal)
    (31 "B.Cu" signal)
    (32 "B.Adhes" user "B.Adhesive")
    (33 "F.Adhes" user "F.Adhesive")
    (34 "B.Paste" user)
    (35 "F.Paste" user)
    (36 "B.SilkS" user "B.Silkscreen")
    (37 "F.SilkS" user "F.Silkscreen")
    (38 "B.Mask" user)
    (39 "F.Mask" user)
    (40 "Dwgs.User" user "User.Drawings")
    (41 "Cmts.User" user "User.Comments")
    (42 "Eco1.User" user "User.Eco1")
    (43 "Eco2.User" user "User.Eco2")
    (44 "Edge.Cuts" user)
    (45 "Margin" user)
    (46 "B.CrtYd" user "B.Courtyard")
    (47 "F.CrtYd" user "F.Courtyard")
    (48 "B.Fab" user)
    (49 "F.Fab" user)
  )
	(footprint "sdi-mipi-bridge-footprints:antmicro-logo_scaled_20mm"
		(layer "F.Cu")
    (at 144.18 99.67)
    (property "Author" "Antmicro")
    (property "License" "Apache-2.0")
    (property "MPN" "")
    (property "Manufacturer" "")
    (property "Sheetfile" "sdi-mipi-bridge.kicad_sch")
    (property "Sheetname" "")
    (fp_text reference "N1" (at 0.05 -5.5) (layer "F.SilkS") hide
        (effects (font (size 0.65 0.65) (thickness 0.15)) (justify left bottom))
    )
    (fp_text value "antmicro_logo" (at -0.101 5.099) (layer "F.SilkS") hide
        (effects (font (size 0.7 0.7) (thickness 0.15)) (justify left bottom))
    )
  )
	(footprint "sdi-mipi-bridge-footprints:C_0402_1005Metric" (layer "F.Cu")
    (at 110.69 117.77 180)
    (descr "Capacitor SMD 0402")
    (tags "capacitor SMD 0402")
    (property "Author" "Antmicro")
    (property "Dielectric" "X7R")
    (property "License" "Apache-2.0")
    (property "MPN" "GRM155R71H103KA88D")
    (property "Manufacturer" "Murata")
    (property "Sheetfile" "sdi-mipi-bridge.kicad_sch")
    (property "Sheetname" "")
    (property "Val" "10n")
    (property "Voltage" "50V")
    (property "ki_description" " ")
    (attr smd)
    (fp_text reference "C22" (at -0.91 0.57) (layer "F.SilkS")
        (effects (font (size 0.65 0.65) (thickness 0.15)) (justify right bottom))
    )
    (fp_text value "C_10n_0402" (at 0 1.4) (layer "F.Fab") hide
        (effects (font (size 0.7 0.7) (thickness 0.15)) (justify right bottom))
    )
    (fp_text user "License: Apache-2.0" (at -0.932 5.17) (layer "F.Fab") hide
        (effects (font (size 0.7 0.7) (thickness 0.15)) (justify right bottom))
    )
    (fp_text user "Author: Antmicro" (at -0.932 4.17) (layer "F.Fab") hide
        (effects (font (size 0.7 0.7) (thickness 0.15)) (justify right bottom))
    )
    (fp_text user "${REFERENCE}" (at -0.932 3.168) (layer "F.Fab") hide
        (effects (font (size 0.7 0.7) (thickness 0.15)) (justify right bottom))
    )
    (fp_rect (start -0.94 -0.47) (end 0.94 0.47)
      (stroke (width 0.05) (type solid)) (fill none) (layer "F.CrtYd"))
    (fp_rect (start -0.499 -0.249) (end 0.499 0.249)
      (stroke (width 0.15) (type solid)) (fill none) (layer "F.Fab"))
    (pad "1" smd roundrect (at -0.484 0 180) (size 0.59 0.64) (layers "F.Cu" "F.Paste" "F.Mask") (roundrect_rratio 0.25)
      (net 3 "GNDA") (pintype "passive"))
    (pad "2" smd roundrect (at 0.484 0 180) (size 0.59 0.64) (layers "F.Cu" "F.Paste" "F.Mask") (roundrect_rratio 0.25)
      (net 57 "VDD") (pintype "passive"))
  )
	(footprint "sdi-mipi-bridge-footprints:Conn_BNC_031-70526-21" (layer "F.Cu")
    (at 91.128 126 -90)
    (property "Author" "Antmicro")
    (property "License" "Apache-2.0")
    (property "MPN" "031-70526-21")
    (property "Manufacturer" "Amphenol")
    (property "Sheetfile" "sdi-mipi-bridge.kicad_sch")
    (property "Sheetname" "")
    (property "ki_description" "RF / Coaxial Connector, BNC Coaxial, Straight Bulkhead Jack, Board Edge / End Launch, 75 ohm")
    (property "ki_keywords" "HORIZONTAL, BULKHEAD, RF, CONNECTOR")
    (attr smd)
    (fp_text reference "J1" (at 0 -13.5 -90 unlocked) (layer "F.SilkS")
        (effects (font (size 0.7 0.7) (thickness 0.15)) (justify left bottom))
    )
    (fp_text value "Conn_BNC_031-70526-21" (at 0 13.9 90) (layer "F.Fab") hide
        (effects (font (size 0.7 0.7) (thickness 0.15)) (justify right bottom))
    )
    (fp_text user "License: Apache-2.0" (at -8.2 16.1 90) (layer "F.Fab") hide
        (effects (font (size 0.7 0.7) (thickness 0.15)) (justify right bottom))
    )
    (fp_text user "${REFERENCE}" (at -8.2 17.3 90) (layer "F.Fab") hide
        (effects (font (size 0.7 0.7) (thickness 0.15)) (justify right bottom))
    )
    (fp_text user "Author: Antmicro" (at -8.2 14.9 90) (layer "F.Fab") hide
        (effects (font (size 0.7 0.7) (thickness 0.15)) (justify right bottom))
    )
    (fp_line (start -8.2 -5.5) (end -8.2 -4.6)
      (stroke (width 0.05) (type solid)) (layer "B.CrtYd"))
    (fp_line (start -8.2 -4.6) (end -7.4 -4.6)
      (stroke (width 0.05) (type solid)) (layer "B.CrtYd"))
    (fp_line (start -7.4 -4.6) (end -7.4 12.9)
      (stroke (width 0.05) (type solid)) (layer "B.CrtYd"))
    (fp_line (start -6.6 -6.6) (end -6.6 -5.5)
      (stroke (width 0.05) (type solid)) (layer "B.CrtYd"))
    (fp_line (start -6.6 -5.5) (end -8.2 -5.5)
      (stroke (width 0.05) (type solid)) (layer "B.CrtYd"))
    (fp_line (start -5.7 -13.6) (end -5.7 -6.6)
      (stroke (width 0.05) (type solid)) (layer "B.CrtYd"))
    (fp_line (start -5.7 -6.6) (end -6.6 -6.6)
      (stroke (width 0.05) (type solid)) (layer "B.CrtYd"))
    (fp_line (start -4.2 -13.6) (end -5.7 -13.6)
      (stroke (width 0.05) (type solid)) (layer "B.CrtYd"))
    (fp_line (start -4.2 -13.6) (end -4.2 -12.9)
      (stroke (width 0.05) (type solid)) (layer "B.CrtYd"))
    (fp_line (start 4.1 -13.6) (end 4.1 -12.9)
      (stroke (width 0.05) (type solid)) (layer "B.CrtYd"))
    (fp_line (start 4.1 -13.6) (end 5.6 -13.6)
      (stroke (width 0.05) (type solid)) (layer "B.CrtYd"))
    (fp_line (start 4.1 -12.9) (end -4.2 -12.9)
      (stroke (width 0.05) (type solid)) (layer "B.CrtYd"))
    (fp_line (start 5.6 -13.6) (end 5.6 -6.6)
      (stroke (width 0.05) (type solid)) (layer "B.CrtYd"))
    (fp_line (start 5.6 -6.6) (end 6.5 -6.6)
      (stroke (width 0.05) (type solid)) (layer "B.CrtYd"))
    (fp_line (start 6.5 -6.6) (end 6.5 -5.5)
      (stroke (width 0.05) (type solid)) (layer "B.CrtYd"))
    (fp_line (start 6.5 -5.5) (end 8.1 -5.5)
      (stroke (width 0.05) (type solid)) (layer "B.CrtYd"))
    (fp_line (start 7.3 -4.6) (end 7.3 12.9)
      (stroke (width 0.05) (type solid)) (layer "B.CrtYd"))
    (fp_line (start 7.3 12.9) (end -7.4 12.9)
      (stroke (width 0.05) (type solid)) (layer "B.CrtYd"))
    (fp_line (start 8.1 -5.5) (end 8.1 -4.6)
      (stroke (width 0.05) (type solid)) (layer "B.CrtYd"))
    (fp_line (start 8.1 -4.6) (end 7.3 -4.6)
      (stroke (width 0.05) (type solid)) (layer "B.CrtYd"))
    (fp_line (start -8.2 -5.5) (end -8.2 -4.6)
      (stroke (width 0.05) (type solid)) (layer "F.CrtYd"))
    (fp_line (start -8.2 -4.6) (end -7.4 -4.6)
      (stroke (width 0.05) (type solid)) (layer "F.CrtYd"))
    (fp_line (start -7.4 -4.6) (end -7.4 12.9)
      (stroke (width 0.05) (type solid)) (layer "F.CrtYd"))
    (fp_line (start -7.4 12.9) (end 7.3 12.9)
      (stroke (width 0.05) (type solid)) (layer "F.CrtYd"))
    (fp_line (start -6.6 -6.6) (end -6.6 -5.5)
      (stroke (width 0.05) (type solid)) (layer "F.CrtYd"))
    (fp_line (start -6.6 -5.5) (end -8.2 -5.5)
      (stroke (width 0.05) (type solid)) (layer "F.CrtYd"))
    (fp_line (start -5.7 -13.6) (end -5.7 -6.6)
      (stroke (width 0.05) (type solid)) (layer "F.CrtYd"))
    (fp_line (start -5.7 -6.6) (end -6.6 -6.6)
      (stroke (width 0.05) (type solid)) (layer "F.CrtYd"))
    (fp_line (start -4.2 -13.6) (end -5.7 -13.6)
      (stroke (width 0.05) (type solid)) (layer "F.CrtYd"))
    (fp_line (start -4.2 -13.6) (end -4.2 -12.9)
      (stroke (width 0.05) (type solid)) (layer "F.CrtYd"))
    (fp_line (start -4.2 -12.9) (end 4.1 -12.9)
      (stroke (width 0.05) (type solid)) (layer "F.CrtYd"))
    (fp_line (start 4.1 -13.6) (end 4.1 -12.9)
      (stroke (width 0.05) (type solid)) (layer "F.CrtYd"))
    (fp_line (start 4.1 -13.6) (end 5.6 -13.6)
      (stroke (width 0.05) (type solid)) (layer "F.CrtYd"))
    (fp_line (start 5.6 -13.6) (end 5.6 -6.6)
      (stroke (width 0.05) (type solid)) (layer "F.CrtYd"))
    (fp_line (start 5.6 -6.6) (end 6.5 -6.6)
      (stroke (width 0.05) (type solid)) (layer "F.CrtYd"))
    (fp_line (start 6.5 -6.6) (end 6.5 -5.5)
      (stroke (width 0.05) (type solid)) (layer "F.CrtYd"))
    (fp_line (start 6.5 -5.5) (end 8.1 -5.5)
      (stroke (width 0.05) (type solid)) (layer "F.CrtYd"))
    (fp_line (start 7.3 -4.6) (end 7.3 12.9)
      (stroke (width 0.05) (type solid)) (layer "F.CrtYd"))
    (fp_line (start 8.1 -5.5) (end 8.1 -4.6)
      (stroke (width 0.05) (type solid)) (layer "F.CrtYd"))
    (fp_line (start 8.1 -4.6) (end 7.3 -4.6)
      (stroke (width 0.05) (type solid)) (layer "F.CrtYd"))
    (pad "1" smd rect (at 0 -7.872 270) (size 1.1 1.75) (layers "F.Cu" "F.Paste" "F.Mask")
      (net 140 "Net-(C31-Pad2)") (pinfunction "1") (pintype "passive"))
    (pad "2" smd rect (at -4.851 -10.221 270) (size 1.1 6.45) (layers "F.Cu" "F.Paste" "F.Mask")
      (net 3 "GNDA") (pinfunction "2") (pintype "passive"))
    (pad "2" smd rect (at 4.849 -10.221 270) (size 1.1 6.45) (layers "F.Cu" "F.Paste" "F.Mask")
      (net 3 "GNDA") (pinfunction "2") (pintype "passive"))
  )
	(footprint "sdi-mipi-bridge-footprints:Conn_BNC_031-70526-21" (layer "F.Cu")
    (at 91.128 107 -90)
    (property "Author" "Antmicro")
    (property "License" "Apache-2.0")
    (property "MPN" "031-70526-21")
    (property "Manufacturer" "Amphenol")
    (property "Sheetfile" "sdi-mipi-bridge.kicad_sch")
    (property "Sheetname" "")
    (property "ki_description" "RF / Coaxial Connector, BNC Coaxial, Straight Bulkhead Jack, Board Edge / End Launch, 75 ohm")
    (property "ki_keywords" "HORIZONTAL, BULKHEAD, RF, CONNECTOR")
    (attr smd)
    (fp_text reference "J2" (at 0 -13.5 -90 unlocked) (layer "F.SilkS")
        (effects (font (size 0.7 0.7) (thickness 0.15)) (justify left bottom))
    )
    (fp_text value "Conn_BNC_031-70526-21" (at 0 13.9 90) (layer "F.Fab") hide
        (effects (font (size 0.7 0.7) (thickness 0.15)) (justify right bottom))
    )
    (fp_text user "${REFERENCE}" (at -8.2 17.3 90) (layer "F.Fab") hide
        (effects (font (size 0.7 0.7) (thickness 0.15)) (justify right bottom))
    )
    (fp_text user "Author: Antmicro" (at -8.2 14.9 90) (layer "F.Fab") hide
        (effects (font (size 0.7 0.7) (thickness 0.15)) (justify right bottom))
    )
    (fp_text user "License: Apache-2.0" (at -8.2 16.1 90) (layer "F.Fab") hide
        (effects (font (size 0.7 0.7) (thickness 0.15)) (justify right bottom))
    )
    (fp_line (start -8.2 -5.5) (end -8.2 -4.6)
      (stroke (width 0.05) (type solid)) (layer "B.CrtYd"))
    (fp_line (start -8.2 -4.6) (end -7.4 -4.6)
      (stroke (width 0.05) (type solid)) (layer "B.CrtYd"))
    (fp_line (start -7.4 -4.6) (end -7.4 12.9)
      (stroke (width 0.05) (type solid)) (layer "B.CrtYd"))
    (fp_line (start -6.6 -6.6) (end -6.6 -5.5)
      (stroke (width 0.05) (type solid)) (layer "B.CrtYd"))
    (fp_line (start -6.6 -5.5) (end -8.2 -5.5)
      (stroke (width 0.05) (type solid)) (layer "B.CrtYd"))
    (fp_line (start -5.7 -13.6) (end -5.7 -6.6)
      (stroke (width 0.05) (type solid)) (layer "B.CrtYd"))
    (fp_line (start -5.7 -6.6) (end -6.6 -6.6)
      (stroke (width 0.05) (type solid)) (layer "B.CrtYd"))
    (fp_line (start -4.2 -13.6) (end -5.7 -13.6)
      (stroke (width 0.05) (type solid)) (layer "B.CrtYd"))
    (fp_line (start -4.2 -13.6) (end -4.2 -12.9)
      (stroke (width 0.05) (type solid)) (layer "B.CrtYd"))
    (fp_line (start 4.1 -13.6) (end 4.1 -12.9)
      (stroke (width 0.05) (type solid)) (layer "B.CrtYd"))
    (fp_line (start 4.1 -13.6) (end 5.6 -13.6)
      (stroke (width 0.05) (type solid)) (layer "B.CrtYd"))
    (fp_line (start 4.1 -12.9) (end -4.2 -12.9)
      (stroke (width 0.05) (type solid)) (layer "B.CrtYd"))
    (fp_line (start 5.6 -13.6) (end 5.6 -6.6)
      (stroke (width 0.05) (type solid)) (layer "B.CrtYd"))
    (fp_line (start 5.6 -6.6) (end 6.5 -6.6)
      (stroke (width 0.05) (type solid)) (layer "B.CrtYd"))
    (fp_line (start 6.5 -6.6) (end 6.5 -5.5)
      (stroke (width 0.05) (type solid)) (layer "B.CrtYd"))
    (fp_line (start 6.5 -5.5) (end 8.1 -5.5)
      (stroke (width 0.05) (type solid)) (layer "B.CrtYd"))
    (fp_line (start 7.3 -4.6) (end 7.3 12.9)
      (stroke (width 0.05) (type solid)) (layer "B.CrtYd"))
    (fp_line (start 7.3 12.9) (end -7.4 12.9)
      (stroke (width 0.05) (type solid)) (layer "B.CrtYd"))
    (fp_line (start 8.1 -5.5) (end 8.1 -4.6)
      (stroke (width 0.05) (type solid)) (layer "B.CrtYd"))
    (fp_line (start 8.1 -4.6) (end 7.3 -4.6)
      (stroke (width 0.05) (type solid)) (layer "B.CrtYd"))
    (fp_line (start -8.2 -5.5) (end -8.2 -4.6)
      (stroke (width 0.05) (type solid)) (layer "F.CrtYd"))
    (fp_line (start -8.2 -4.6) (end -7.4 -4.6)
      (stroke (width 0.05) (type solid)) (layer "F.CrtYd"))
    (fp_line (start -7.4 -4.6) (end -7.4 12.9)
      (stroke (width 0.05) (type solid)) (layer "F.CrtYd"))
    (fp_line (start -7.4 12.9) (end 7.3 12.9)
      (stroke (width 0.05) (type solid)) (layer "F.CrtYd"))
    (fp_line (start -6.6 -6.6) (end -6.6 -5.5)
      (stroke (width 0.05) (type solid)) (layer "F.CrtYd"))
    (fp_line (start -6.6 -5.5) (end -8.2 -5.5)
      (stroke (width 0.05) (type solid)) (layer "F.CrtYd"))
    (fp_line (start -5.7 -13.6) (end -5.7 -6.6)
      (stroke (width 0.05) (type solid)) (layer "F.CrtYd"))
    (fp_line (start -5.7 -6.6) (end -6.6 -6.6)
      (stroke (width 0.05) (type solid)) (layer "F.CrtYd"))
    (fp_line (start -4.2 -13.6) (end -5.7 -13.6)
      (stroke (width 0.05) (type solid)) (layer "F.CrtYd"))
    (fp_line (start -4.2 -13.6) (end -4.2 -12.9)
      (stroke (width 0.05) (type solid)) (layer "F.CrtYd"))
    (fp_line (start -4.2 -12.9) (end 4.1 -12.9)
      (stroke (width 0.05) (type solid)) (layer "F.CrtYd"))
    (fp_line (start 4.1 -13.6) (end 4.1 -12.9)
      (stroke (width 0.05) (type solid)) (layer "F.CrtYd"))
    (fp_line (start 4.1 -13.6) (end 5.6 -13.6)
      (stroke (width 0.05) (type solid)) (layer "F.CrtYd"))
    (fp_line (start 5.6 -13.6) (end 5.6 -6.6)
      (stroke (width 0.05) (type solid)) (layer "F.CrtYd"))
    (fp_line (start 5.6 -6.6) (end 6.5 -6.6)
      (stroke (width 0.05) (type solid)) (layer "F.CrtYd"))
    (fp_line (start 6.5 -6.6) (end 6.5 -5.5)
      (stroke (width 0.05) (type solid)) (layer "F.CrtYd"))
    (fp_line (start 6.5 -5.5) (end 8.1 -5.5)
      (stroke (width 0.05) (type solid)) (layer "F.CrtYd"))
    (fp_line (start 7.3 -4.6) (end 7.3 12.9)
      (stroke (width 0.05) (type solid)) (layer "F.CrtYd"))
    (fp_line (start 8.1 -5.5) (end 8.1 -4.6)
      (stroke (width 0.05) (type solid)) (layer "F.CrtYd"))
    (fp_line (start 8.1 -4.6) (end 7.3 -4.6)
      (stroke (width 0.05) (type solid)) (layer "F.CrtYd"))
    (pad "1" smd rect (at 0 -7.872 270) (size 1.1 1.75) (layers "F.Cu" "F.Paste" "F.Mask")
      (net 69 "Net-(C43-Pad1)") (pinfunction "1") (pintype "passive"))
    (pad "2" smd rect (at -4.851 -10.221 270) (size 1.1 6.45) (layers "F.Cu" "F.Paste" "F.Mask")
      (net 3 "GNDA") (pinfunction "2") (pintype "passive"))
    (pad "2" smd rect (at 4.849 -10.221 270) (size 1.1 6.45) (layers "F.Cu" "F.Paste" "F.Mask")
      (net 3 "GNDA") (pinfunction "2") (pintype "passive"))
  )
	(footprint "sdi-mipi-bridge-footprints:TDFN-8-1EP_2x2mm_P0.5mm" (layer "F.Cu")
    (at 129.6 133.303)
    (property "Author" "Antmicro")
    (property "License" "Apache-2.0")
    (property "MPN" "MAX8902B")
    (property "Manufacturer" "Maxim Integrated Products")
    (property "Sheetfile" "sdi-mipi-bridge.kicad_sch")
    (property "Sheetname" "")
    (property "ki_description" "LDO Voltage Regulator, Adjustable, 1.7V to 5.5V input, 150 mV drop., 0.6-5.3V/0.5A out, TDFN-8")
    (property "ki_keywords" "IC")
    (attr smd)
    (fp_text reference "U1" (at -1.6 2.9) (layer "F.SilkS")
        (effects (font (size 0.7 0.7) (thickness 0.15)) (justify left bottom))
    )
    (fp_text value "MAX8902B" (at 0.049 -2.053) (layer "F.Fab") hide
        (effects (font (size 0.7 0.7) (thickness 0.15)) (justify left bottom))
    )
    (fp_text user "." (at -1.9 -1.2 unlocked) (layer "F.SilkS") hide
        (effects (font (size 0.7 0.7) (thickness 0.15)) (justify left bottom))
    )
    (fp_text user "Author: Antmicro" (at -1.6 4.9) (layer "F.Fab") hide
        (effects (font (size 0.7 0.7) (thickness 0.15)) (justify left bottom))
    )
    (fp_text user "License: Apache-2.0" (at -1.6 7.3) (layer "F.Fab") hide
        (effects (font (size 0.7 0.7) (thickness 0.15)) (justify left bottom))
    )
    (fp_text user "${REFERENCE}" (at -1.6 6.1) (layer "F.Fab") hide
        (effects (font (size 0.7 0.7) (thickness 0.15)) (justify left bottom))
    )
    (fp_line (start -0.6 1.05) (end 0.499 1.05)
      (stroke (width 0.15) (type solid)) (layer "F.SilkS"))
    (fp_line (start 0.499 -1.051) (end -1 -1.051)
      (stroke (width 0.15) (type solid)) (layer "F.SilkS"))
    (fp_rect (start -1.6 -1.5) (end 1.6 1.498)
      (stroke (width 0.05) (type solid)) (fill none) (layer "F.CrtYd"))
    (fp_line (start -1 -0.6) (end -0.6 -1)
      (stroke (width 0.15) (type solid)) (layer "F.Fab"))
    (fp_line (start -1 1) (end -1 -0.6)
      (stroke (width 0.15) (type solid)) (layer "F.Fab"))
    (fp_line (start -0.6 -1) (end 1 -1)
      (stroke (width 0.15) (type solid)) (layer "F.Fab"))
    (fp_line (start 1 -1) (end 1 1)
      (stroke (width 0.15) (type solid)) (layer "F.Fab"))
    (fp_line (start 1 1) (end -1 1)
      (stroke (width 0.15) (type solid)) (layer "F.Fab"))
    (pad "1" smd roundrect (at -0.926 -0.75) (size 0.7 0.25) (layers "F.Cu" "F.Paste" "F.Mask") (roundrect_rratio 0.25)
      (net 6 "+3V3") (pinfunction "IN") (pintype "input"))
    (pad "2" smd roundrect (at -0.926 -0.252) (size 0.7 0.25) (layers "F.Cu" "F.Paste" "F.Mask") (roundrect_rratio 0.25)
      (net 1 "GNDREF") (pinfunction "GND") (pintype "power_in"))
    (pad "3" smd roundrect (at -0.926 0.246) (size 0.7 0.25) (layers "F.Cu" "F.Paste" "F.Mask") (roundrect_rratio 0.25)
      (net 6 "+3V3") (pinfunction "EN") (pintype "input"))
    (pad "4" smd roundrect (at -0.926 0.748) (size 0.7 0.25) (layers "F.Cu" "F.Paste" "F.Mask") (roundrect_rratio 0.25)
      (net 1 "GNDREF") (pinfunction "GS") (pintype "input"))
    (pad "5" smd roundrect (at 0.925 0.748) (size 0.7 0.25) (layers "F.Cu" "F.Paste" "F.Mask") (roundrect_rratio 0.25)
      (net 129 "Net-(U1-~{POK})") (pinfunction "~{POK}") (pintype "output"))
    (pad "6" smd roundrect (at 0.925 0.246) (size 0.7 0.25) (layers "F.Cu" "F.Paste" "F.Mask") (roundrect_rratio 0.25)
      (net 71 "Net-(U1-FB)") (pinfunction "FB") (pintype "input"))
    (pad "7" smd roundrect (at 0.925 -0.252) (size 0.7 0.25) (layers "F.Cu" "F.Paste" "F.Mask") (roundrect_rratio 0.25)
      (net 25 "Net-(U1-BYP)") (pinfunction "BYP") (pintype "input"))
    (pad "8" smd roundrect (at 0.925 -0.75) (size 0.7 0.25) (layers "F.Cu" "F.Paste" "F.Mask") (roundrect_rratio 0.25)
      (net 2 "+1V2") (pinfunction "OUT") (pintype "output"))
    (pad "9" smd roundrect (at 0 -0.003) (size 0.64 1.37) (layers "F.Cu" "F.Paste" "F.Mask") (roundrect_rratio 0.25)
      (net 1 "GNDREF") (pinfunction "EP") (pintype "passive") (zone_connect 0))
  )
)
